(kicad_pcb
	(version 20260206)
	(generator "pcbnew")
	(generator_version "10.0")
	(general
		(thickness 1.6)
		(legacy_teardrops no)
	)
	(paper "A4")
	(title_block
		(title "Bryce Canyon_IOM_M2_16342-2_OCP.brd")
		(comment 1 "Bryce Canyon / footprints 329-336 of 1146")
	)
	(layers
		(0 "F.Cu" signal "TOP")
		(4 "In1.Cu" signal "L2GND")
		(6 "In2.Cu" signal "L3")
		(8 "In3.Cu" signal "L4VCC")
		(10 "In4.Cu" signal "L5VCC")
		(12 "In5.Cu" signal "L6")
		(14 "In6.Cu" signal "L7GND")
		(2 "B.Cu" signal "BOTTOM")
		(9 "F.Adhes" user "F.Adhesive")
		(11 "B.Adhes" user "B.Adhesive")
		(13 "F.Paste" user "Package Geometry/Pastemask Top")
		(15 "B.Paste" user "Package Geometry/Pastemask Bottom")
		(5 "F.SilkS" user "Ref Des/Silkscreen Top")
		(7 "B.SilkS" user "Ref Des/Silkscreen Bottom")
		(1 "F.Mask" user "Board Geometry/Soldermask Top")
		(3 "B.Mask" user "Board Geometry/Soldermask Bottom")
		(17 "Dwgs.User" user "User.Drawings")
		(19 "Cmts.User" user "User.Comments")
		(21 "Eco1.User" user "User.Eco1")
		(23 "Eco2.User" user "User.Eco2")
		(25 "Edge.Cuts" user "Board Geometry/Outline")
		(27 "Margin" user)
		(31 "F.CrtYd" user "Package Geometry/Place Bound Top")
		(29 "B.CrtYd" user "Package Geometry/Place Bound Bottom")
		(35 "F.Fab" user "Ref Des/Assembly Top")
		(33 "B.Fab" user "Ref Des/Assembly Bottom")
	)
	(footprint ""
		(layer "F.Cu")
		(at 49.440846 -131.737354 180)
		(property "Reference" "R178"
			(at 0 0 180)
			(layer "F.SilkS")
			(hide yes)
			(effects
				(font
					(size 1.27 1.27)
				)
			)
		)
		(property "Value" "0R2J-2-GP"
			(at 0.064008 -3.993896 180)
			(unlocked yes)
			(layer "F.Fab")
			(hide yes)
			(effects
				(font
					(size 1.016 1.016)
					(thickness 0.1524)
				)
			)
		)
		(property "Device Type" "R402H16"
			(at 0.064008 -5.517896 180)
			(unlocked yes)
			(layer "F.Fab")
			(hide yes)
			(effects
				(font
					(size 1.016 1.016)
					(thickness 0.1524)
				)
			)
		)
		(duplicate_pad_numbers_are_jumpers no)
		(fp_line
			(start 0.508 -0.9398)
			(end -0.508 -0.9398)
			(stroke
				(width 0.1524)
				(type default)
			)
			(layer "F.SilkS")
		)
		(fp_line
			(start -0.508 -0.9398)
			(end -0.508 0.9398)
			(stroke
				(width 0.1524)
				(type default)
			)
			(layer "F.SilkS")
		)
		(fp_rect
			(start -0.508 0.9398)
			(end 0.508 -0.9398)
			(stroke
				(width 0)
				(type default)
			)
			(fill no)
			(layer "F.CrtYd")
		)
		(fp_rect
			(start -0.508 0.9398)
			(end 0.508 -0.9398)
			(stroke
				(width 0)
				(type default)
			)
			(fill no)
			(layer "F.Fab")
		)
		(pad "1" smd custom
			(at 0 -0.4445 180)
			(size 0.1397 0.1397)
			(layers "F.Cu" "F.Mask" "F.Paste")
			(net "I2C_TPM_SDA")
			(options
				(clearance outline)
				(anchor circle)
			)
			(primitives
				(gr_poly
					(pts
						(arc
							(start -0.1778 -0.2794)
							(mid -0.249642 -0.249642)
							(end -0.2794 -0.1778)
						)
						(arc
							(start -0.2794 0.1778)
							(mid -0.249642 0.249642)
							(end -0.1778 0.2794)
						)
						(arc
							(start 0.1778 0.2794)
							(mid 0.249642 0.249642)
							(end 0.2794 0.1778)
						)
						(arc
							(start 0.2794 -0.1778)
							(mid 0.249642 -0.249642)
							(end 0.1778 -0.2794)
						)
					)
					(width 0)
					(fill yes)
				)
			)
		)
		(pad "2" smd custom
			(at 0 0.4445 180)
			(size 0.1397 0.1397)
			(layers "F.Cu" "F.Mask" "F.Paste")
			(net "BMC_SMB14_DAT")
			(options
				(clearance outline)
				(anchor circle)
			)
			(primitives
				(gr_poly
					(pts
						(arc
							(start -0.1778 -0.2794)
							(mid -0.249642 -0.249642)
							(end -0.2794 -0.1778)
						)
						(arc
							(start -0.2794 0.1778)
							(mid -0.249642 0.249642)
							(end -0.1778 0.2794)
						)
						(arc
							(start 0.1778 0.2794)
							(mid 0.249642 0.249642)
							(end 0.2794 0.1778)
						)
						(arc
							(start 0.2794 -0.1778)
							(mid 0.249642 -0.249642)
							(end 0.1778 -0.2794)
						)
					)
					(width 0)
					(fill yes)
				)
			)
		)
	)
	(footprint ""
		(layer "F.Cu")
		(at 17.7546 -129.1082 180)
		(property "Reference" "R220"
			(at 0 0 180)
			(layer "F.SilkS")
			(hide yes)
			(effects
				(font
					(size 1.27 1.27)
				)
			)
		)
		(property "Value" "120R2F-GP"
			(at 0.064008 -3.993896 180)
			(unlocked yes)
			(layer "F.Fab")
			(hide yes)
			(effects
				(font
					(size 1.016 1.016)
					(thickness 0.1524)
				)
			)
		)
		(property "Device Type" "R402H16"
			(at 0.064008 -5.517896 180)
			(unlocked yes)
			(layer "F.Fab")
			(hide yes)
			(effects
				(font
					(size 1.016 1.016)
					(thickness 0.1524)
				)
			)
		)
		(duplicate_pad_numbers_are_jumpers no)
		(fp_line
			(start 0.508 -0.9398)
			(end -0.508 -0.9398)
			(stroke
				(width 0.1524)
				(type default)
			)
			(layer "F.SilkS")
		)
		(fp_line
			(start -0.508 -0.9398)
			(end -0.508 0.9398)
			(stroke
				(width 0.1524)
				(type default)
			)
			(layer "F.SilkS")
		)
		(fp_rect
			(start -0.508 0.9398)
			(end 0.508 -0.9398)
			(stroke
				(width 0)
				(type default)
			)
			(fill no)
			(layer "F.CrtYd")
		)
		(fp_rect
			(start -0.508 0.9398)
			(end 0.508 -0.9398)
			(stroke
				(width 0)
				(type default)
			)
			(fill no)
			(layer "F.Fab")
		)
		(pad "1" smd custom
			(at 0 -0.4445 180)
			(size 0.1397 0.1397)
			(layers "F.Cu" "F.Mask" "F.Paste")
			(net "GND")
			(options
				(clearance outline)
				(anchor circle)
			)
			(primitives
				(gr_poly
					(pts
						(arc
							(start -0.1778 -0.2794)
							(mid -0.249642 -0.249642)
							(end -0.2794 -0.1778)
						)
						(arc
							(start -0.2794 0.1778)
							(mid -0.249642 0.249642)
							(end -0.1778 0.2794)
						)
						(arc
							(start 0.1778 0.2794)
							(mid 0.249642 0.249642)
							(end 0.2794 0.1778)
						)
						(arc
							(start 0.2794 -0.1778)
							(mid 0.249642 -0.249642)
							(end 0.1778 -0.2794)
						)
					)
					(width 0)
					(fill yes)
				)
			)
		)
		(pad "2" smd custom
			(at 0 0.4445 180)
			(size 0.1397 0.1397)
			(layers "F.Cu" "F.Mask" "F.Paste")
			(net "DDR4_ACT")
			(options
				(clearance outline)
				(anchor circle)
			)
			(primitives
				(gr_poly
					(pts
						(arc
							(start -0.1778 -0.2794)
							(mid -0.249642 -0.249642)
							(end -0.2794 -0.1778)
						)
						(arc
							(start -0.2794 0.1778)
							(mid -0.249642 0.249642)
							(end -0.1778 0.2794)
						)
						(arc
							(start 0.1778 0.2794)
							(mid 0.249642 0.249642)
							(end 0.2794 0.1778)
						)
						(arc
							(start 0.2794 -0.1778)
							(mid 0.249642 -0.249642)
							(end 0.1778 -0.2794)
						)
					)
					(width 0)
					(fill yes)
				)
			)
		)
	)
	(footprint ""
		(layer "F.Cu")
		(at 39.839646 -180.64861 90)
		(property "Reference" "R498"
			(at 0 0 90)
			(layer "F.SilkS")
			(hide yes)
			(effects
				(font
					(size 1.27 1.27)
				)
			)
		)
		(property "Value" "0R2J-2-GP"
			(at 0.064008 -3.993896 90)
			(unlocked yes)
			(layer "F.Fab")
			(hide yes)
			(effects
				(font
					(size 1.016 1.016)
					(thickness 0.1524)
				)
			)
		)
		(property "Device Type" "R402H16"
			(at 0.064008 -5.517896 90)
			(unlocked yes)
			(layer "F.Fab")
			(hide yes)
			(effects
				(font
					(size 1.016 1.016)
					(thickness 0.1524)
				)
			)
		)
		(duplicate_pad_numbers_are_jumpers no)
		(fp_line
			(start 0.508 -0.9398)
			(end -0.508 -0.9398)
			(stroke
				(width 0.1524)
				(type default)
			)
			(layer "F.SilkS")
		)
		(fp_line
			(start -0.508 -0.9398)
			(end -0.508 0.9398)
			(stroke
				(width 0.1524)
				(type default)
			)
			(layer "F.SilkS")
		)
		(fp_rect
			(start -0.508 0.9398)
			(end 0.508 -0.9398)
			(stroke
				(width 0)
				(type default)
			)
			(fill no)
			(layer "F.CrtYd")
		)
		(fp_rect
			(start -0.508 0.9398)
			(end 0.508 -0.9398)
			(stroke
				(width 0)
				(type default)
			)
			(fill no)
			(layer "F.Fab")
		)
		(pad "1" smd custom
			(at 0 -0.4445 90)
			(size 0.1397 0.1397)
			(layers "F.Cu" "F.Mask" "F.Paste")
			(net "P3V3_STBY_ROVP")
			(options
				(clearance outline)
				(anchor circle)
			)
			(primitives
				(gr_poly
					(pts
						(arc
							(start -0.1778 -0.2794)
							(mid -0.249642 -0.249642)
							(end -0.2794 -0.1778)
						)
						(arc
							(start -0.2794 0.1778)
							(mid -0.249642 0.249642)
							(end -0.1778 0.2794)
						)
						(arc
							(start 0.1778 0.2794)
							(mid 0.249642 0.249642)
							(end 0.2794 0.1778)
						)
						(arc
							(start 0.2794 -0.1778)
							(mid 0.249642 -0.249642)
							(end 0.1778 -0.2794)
						)
					)
					(width 0)
					(fill yes)
				)
			)
		)
		(pad "2" smd custom
			(at 0 0.4445 90)
			(size 0.1397 0.1397)
			(layers "F.Cu" "F.Mask" "F.Paste")
			(net "AGND_P3V3_STBY")
			(options
				(clearance outline)
				(anchor circle)
			)
			(primitives
				(gr_poly
					(pts
						(arc
							(start -0.1778 -0.2794)
							(mid -0.249642 -0.249642)
							(end -0.2794 -0.1778)
						)
						(arc
							(start -0.2794 0.1778)
							(mid -0.249642 0.249642)
							(end -0.1778 0.2794)
						)
						(arc
							(start 0.1778 0.2794)
							(mid 0.249642 0.249642)
							(end 0.2794 0.1778)
						)
						(arc
							(start 0.2794 -0.1778)
							(mid 0.249642 -0.249642)
							(end 0.1778 -0.2794)
						)
					)
					(width 0)
					(fill yes)
				)
			)
		)
	)
	(footprint ""
		(layer "F.Cu")
		(at 167.426132 -137.220198 -135)
		(property "Reference" "VIA65"
			(at 0 0 225)
			(layer "F.SilkS")
			(hide yes)
			(effects
				(font
					(size 1.27 1.27)
				)
			)
		)
		(property "Value" "85OHM-8L-1D6MM-L16L18-GP"
			(at 4.064105 0.609655 225)
			(unlocked yes)
			(layer "F.Fab")
			(hide yes)
			(effects
				(font
					(size 1.016 1.016)
					(thickness 0.1524)
				)
			)
		)
		(property "Device Type" "VIA-PCIE-4P-368076"
			(at 4.064105 -0.914474 225)
			(unlocked yes)
			(layer "F.Fab")
			(hide yes)
			(effects
				(font
					(size 1.016 1.016)
					(thickness 0.1524)
				)
			)
		)
		(duplicate_pad_numbers_are_jumpers no)
		(fp_poly
			(pts
				(xy -1.841491 -0.381057) (xy 1.841509 -0.381058) (xy 1.841508 0.380942) (xy -1.841491 0.380942)
			)
			(stroke
				(width 0)
				(type default)
			)
			(fill no)
			(layer "F.CrtYd")
		)
		(fp_poly
			(pts
				(xy -1.841491 -0.381057) (xy 1.841509 -0.381058) (xy 1.841508 0.380942) (xy -1.841491 0.380942)
			)
			(stroke
				(width 0)
				(type default)
			)
			(fill no)
			(layer "F.Fab")
		)
		(pad "1" thru_hole circle
			(at -1.460499 0 225)
			(size 0.508 0.508)
			(drill 0.254)
			(layers "*.Cu" "*.Mask")
			(remove_unused_layers no)
			(net "GND")
			(clearance 0.127)
			(thermal_gap 0.127)
		)
		(pad "2" thru_hole circle
			(at -0.4445 0 225)
			(size 0.508 0.508)
			(drill 0.254)
			(layers "*.Cu" "*.Mask")
			(remove_unused_layers no)
			(net "PCIE_IOM_TO_COMP_15_DP")
			(clearance 0.127)
			(thermal_gap 0.127)
		)
		(pad "3" thru_hole circle
			(at 0.4445 0 225)
			(size 0.508 0.508)
			(drill 0.254)
			(layers "*.Cu" "*.Mask")
			(remove_unused_layers no)
			(net "PCIE_IOM_TO_COMP_15_DN")
			(clearance 0.127)
			(thermal_gap 0.127)
		)
		(pad "4" thru_hole circle
			(at 1.460499 0 225)
			(size 0.508 0.508)
			(drill 0.254)
			(layers "*.Cu" "*.Mask")
			(remove_unused_layers no)
			(net "GND")
			(clearance 0.127)
			(thermal_gap 0.127)
		)
	)
	(footprint ""
		(layer "F.Cu")
		(at 99.03333 -144.381474 -90)
		(property "Reference" "R427"
			(at 0 0 270)
			(layer "F.SilkS")
			(hide yes)
			(effects
				(font
					(size 1.27 1.27)
				)
			)
		)
		(property "Value" "0R2J-2-GP"
			(at 0.064008 -3.993896 270)
			(unlocked yes)
			(layer "F.Fab")
			(hide yes)
			(effects
				(font
					(size 1.016 1.016)
					(thickness 0.1524)
				)
			)
		)
		(property "Device Type" "R402H16"
			(at 0.064008 -5.517896 270)
			(unlocked yes)
			(layer "F.Fab")
			(hide yes)
			(effects
				(font
					(size 1.016 1.016)
					(thickness 0.1524)
				)
			)
		)
		(duplicate_pad_numbers_are_jumpers no)
		(fp_line
			(start -0.508 -0.9398)
			(end -0.508 0.9398)
			(stroke
				(width 0.1524)
				(type default)
			)
			(layer "F.SilkS")
		)
		(fp_line
			(start 0.508 -0.9398)
			(end -0.508 -0.9398)
			(stroke
				(width 0.1524)
				(type default)
			)
			(layer "F.SilkS")
		)
		(fp_rect
			(start -0.508 0.9398)
			(end 0.508 -0.9398)
			(stroke
				(width 0)
				(type default)
			)
			(fill no)
			(layer "F.CrtYd")
		)
		(fp_rect
			(start -0.508 0.9398)
			(end 0.508 -0.9398)
			(stroke
				(width 0)
				(type default)
			)
			(fill no)
			(layer "F.Fab")
		)
		(pad "1" smd custom
			(at 0 -0.4445 270)
			(size 0.1397 0.1397)
			(layers "F.Cu" "F.Mask" "F.Paste")
			(net "I2C_DEBUG_SCL_L")
			(options
				(clearance outline)
				(anchor circle)
			)
			(primitives
				(gr_poly
					(pts
						(arc
							(start -0.1778 -0.2794)
							(mid -0.249642 -0.249642)
							(end -0.2794 -0.1778)
						)
						(arc
							(start -0.2794 0.1778)
							(mid -0.249642 0.249642)
							(end -0.1778 0.2794)
						)
						(arc
							(start 0.1778 0.2794)
							(mid 0.249642 0.249642)
							(end 0.2794 0.1778)
						)
						(arc
							(start 0.2794 -0.1778)
							(mid 0.249642 -0.249642)
							(end 0.1778 -0.2794)
						)
					)
					(width 0)
					(fill yes)
				)
			)
		)
		(pad "2" smd custom
			(at 0 0.4445 270)
			(size 0.1397 0.1397)
			(layers "F.Cu" "F.Mask" "F.Paste")
			(net "I2C_DEBUG_SCL_R")
			(options
				(clearance outline)
				(anchor circle)
			)
			(primitives
				(gr_poly
					(pts
						(arc
							(start -0.1778 -0.2794)
							(mid -0.249642 -0.249642)
							(end -0.2794 -0.1778)
						)
						(arc
							(start -0.2794 0.1778)
							(mid -0.249642 0.249642)
							(end -0.1778 0.2794)
						)
						(arc
							(start 0.1778 0.2794)
							(mid 0.249642 0.249642)
							(end 0.2794 0.1778)
						)
						(arc
							(start 0.2794 -0.1778)
							(mid 0.249642 -0.249642)
							(end 0.1778 -0.2794)
						)
					)
					(width 0)
					(fill yes)
				)
			)
		)
	)
	(footprint ""
		(layer "F.Cu")
		(at 62.8142 -138.176 90)
		(property "Reference" "TP74"
			(at 0 0 90)
			(layer "F.SilkS")
			(hide yes)
			(effects
				(font
					(size 1.27 1.27)
				)
			)
		)
		(property "Value" "TPAD28-2-GP"
			(at -0.0127 -1.6637 90)
			(unlocked yes)
			(layer "F.Fab")
			(hide yes)
			(effects
				(font
					(size 1.016 1.016)
					(thickness 0.1524)
				)
			)
		)
		(property "Device Type" "TPAD28"
			(at -0.0127 -3.1877 90)
			(unlocked yes)
			(layer "F.Fab")
			(hide yes)
			(effects
				(font
					(size 1.016 1.016)
					(thickness 0.1524)
				)
			)
		)
		(duplicate_pad_numbers_are_jumpers no)
		(fp_poly
			(pts
				(arc
					(start 0 0.3556)
					(mid 0 -0.3556)
					(end 0 0.3556)
				)
			)
			(stroke
				(width 0)
				(type default)
			)
			(fill no)
			(layer "F.CrtYd")
		)
		(fp_poly
			(pts
				(arc
					(start 0 0.6096)
					(mid 0 -0.6096)
					(end 0 0.6096)
				)
			)
			(stroke
				(width 0)
				(type default)
			)
			(fill no)
			(layer "F.Fab")
		)
		(pad "1" smd circle
			(at 0 0 90)
			(size 0.7112 0.7112)
			(layers "F.Cu" "F.Mask" "F.Paste")
			(net "TP_BMC_GPIOI2")
		)
	)
	(footprint ""
		(layer "F.Cu")
		(at 88.814148 -61.517022 -90)
		(property "Reference" "R5"
			(at 0 0 270)
			(layer "F.SilkS")
			(hide yes)
			(effects
				(font
					(size 1.27 1.27)
				)
			)
		)
		(property "Value" "0R2J-2-GP"
			(at 0.064008 -3.993896 270)
			(unlocked yes)
			(layer "F.Fab")
			(hide yes)
			(effects
				(font
					(size 1.016 1.016)
					(thickness 0.1524)
				)
			)
		)
		(property "Device Type" "R402H16"
			(at 0.064008 -5.517896 270)
			(unlocked yes)
			(layer "F.Fab")
			(hide yes)
			(effects
				(font
					(size 1.016 1.016)
					(thickness 0.1524)
				)
			)
		)
		(duplicate_pad_numbers_are_jumpers no)
		(fp_line
			(start -0.508 -0.9398)
			(end -0.508 0.9398)
			(stroke
				(width 0.1524)
				(type default)
			)
			(layer "F.SilkS")
		)
		(fp_line
			(start 0.508 -0.9398)
			(end -0.508 -0.9398)
			(stroke
				(width 0.1524)
				(type default)
			)
			(layer "F.SilkS")
		)
		(fp_rect
			(start -0.508 0.9398)
			(end 0.508 -0.9398)
			(stroke
				(width 0)
				(type default)
			)
			(fill no)
			(layer "F.CrtYd")
		)
		(fp_rect
			(start -0.508 0.9398)
			(end 0.508 -0.9398)
			(stroke
				(width 0)
				(type default)
			)
			(fill no)
			(layer "F.Fab")
		)
		(pad "1" smd custom
			(at 0 -0.4445 270)
			(size 0.1397 0.1397)
			(layers "F.Cu" "F.Mask" "F.Paste")
			(net "NCSI_RCSDV")
			(options
				(clearance outline)
				(anchor circle)
			)
			(primitives
				(gr_poly
					(pts
						(arc
							(start -0.1778 -0.2794)
							(mid -0.249642 -0.249642)
							(end -0.2794 -0.1778)
						)
						(arc
							(start -0.2794 0.1778)
							(mid -0.249642 0.249642)
							(end -0.1778 0.2794)
						)
						(arc
							(start 0.1778 0.2794)
							(mid 0.249642 0.249642)
							(end 0.2794 0.1778)
						)
						(arc
							(start 0.2794 -0.1778)
							(mid 0.249642 -0.249642)
							(end 0.1778 -0.2794)
						)
					)
					(width 0)
					(fill yes)
				)
			)
		)
		(pad "2" smd custom
			(at 0 0.4445 270)
			(size 0.1397 0.1397)
			(layers "F.Cu" "F.Mask" "F.Paste")
			(net "NCSI_RCSDV_R")
			(options
				(clearance outline)
				(anchor circle)
			)
			(primitives
				(gr_poly
					(pts
						(arc
							(start -0.1778 -0.2794)
							(mid -0.249642 -0.249642)
							(end -0.2794 -0.1778)
						)
						(arc
							(start -0.2794 0.1778)
							(mid -0.249642 0.249642)
							(end -0.1778 0.2794)
						)
						(arc
							(start 0.1778 0.2794)
							(mid 0.249642 0.249642)
							(end 0.2794 0.1778)
						)
						(arc
							(start 0.2794 -0.1778)
							(mid 0.249642 -0.249642)
							(end 0.1778 -0.2794)
						)
					)
					(width 0)
					(fill yes)
				)
			)
		)
	)
	(footprint ""
		(layer "F.Cu")
		(at 18.737072 -15.68577 180)
		(property "Reference" "C26"
			(at 0 0 180)
			(layer "F.SilkS")
			(hide yes)
			(effects
				(font
					(size 1.27 1.27)
				)
			)
		)
		(property "Value" "SC1U16V3KX-5GP"
			(at 0 -2.8194 180)
			(unlocked yes)
			(layer "F.Fab")
			(hide yes)
			(effects
				(font
					(size 1.016 1.016)
					(thickness 0.1524)
				)
			)
		)
		(property "Device Type" "C603H36"
			(at 0 -4.3434 180)
			(unlocked yes)
			(layer "F.Fab")
			(hide yes)
			(effects
				(font
					(size 1.016 1.016)
					(thickness 0.1524)
				)
			)
		)
		(duplicate_pad_numbers_are_jumpers no)
		(fp_line
			(start 0.508 0)
			(end -0.508 0)
			(stroke
				(width 0.2032)
				(type default)
			)
			(layer "F.SilkS")
		)
		(fp_rect
			(start -0.5842 1.3335)
			(end 0.5842 -1.3335)
			(stroke
				(width 0)
				(type default)
			)
			(fill no)
			(layer "F.CrtYd")
		)
		(fp_rect
			(start -0.5842 1.3335)
			(end 0.5842 -1.3335)
			(stroke
				(width 0)
				(type default)
			)
			(fill no)
			(layer "F.Fab")
		)
		(pad "1" smd custom
			(at 0 -0.762 180)
			(size 0.2159 0.2159)
			(layers "F.Cu" "F.Mask" "F.Paste")
			(net "FP_PWR_BTN_N")
			(options
				(clearance outline)
				(anchor circle)
			)
			(primitives
				(gr_poly
					(pts
						(arc
							(start -0.3302 -0.4318)
							(mid -0.402042 -0.402042)
							(end -0.4318 -0.3302)
						)
						(arc
							(start -0.4318 0.3302)
							(mid -0.402042 0.402042)
							(end -0.3302 0.4318)
						)
						(arc
							(start 0.3302 0.4318)
							(mid 0.402042 0.402042)
							(end 0.4318 0.3302)
						)
						(arc
							(start 0.4318 -0.3302)
							(mid 0.402042 -0.402042)
							(end 0.3302 -0.4318)
						)
					)
					(width 0)
					(fill yes)
				)
			)
		)
		(pad "2" smd custom
			(at 0 0.762 180)
			(size 0.2159 0.2159)
			(layers "F.Cu" "F.Mask" "F.Paste")
			(net "GND")
			(options
				(clearance outline)
				(anchor circle)
			)
			(primitives
				(gr_poly
					(pts
						(arc
							(start -0.3302 -0.4318)
							(mid -0.402042 -0.402042)
							(end -0.4318 -0.3302)
						)
						(arc
							(start -0.4318 0.3302)
							(mid -0.402042 0.402042)
							(end -0.3302 0.4318)
						)
						(arc
							(start 0.3302 0.4318)
							(mid 0.402042 0.402042)
							(end 0.4318 0.3302)
						)
						(arc
							(start 0.4318 -0.3302)
							(mid 0.402042 -0.402042)
							(end 0.3302 -0.4318)
						)
					)
					(width 0)
					(fill yes)
				)
			)
		)
	)
)
